# SCM (Grand Teton) — schematic netlist excerpt (pin names and nets, part order shuffled) for the footprints in the layout excerpt that follows; sources: Cadence DE-HDL packaged netlist, KiCad conversion of 12092022_DA0F0TMDCD0_F0T_Management_Board_D_brd_V3_OCP.brd

R580  Q_RES  33.2 1% CHIP  pkg 0402LF  page 12 : A = SMB_BMC_MM9_R_SCL ; B = SMB_BMC_MM9_SCL
C76  Q_CAP  0.1UF 25V 10% X7R  pkg 0402  page 16 : A = P1V2_AUX ; B = GND

(kicad_pcb
	(version 20260206)
	(generator "pcbnew")
	(generator_version "10.0")
	(general
		(thickness 1.6)
		(legacy_teardrops no)
	)
	(paper "A4")
	(title_block
		(title "12092022_DA0F0TMDCD0_F0T_Management_Board_D_brd_V3_OCP.brd")
		(comment 1 "Grand Teton / footprints 1165-1166 of 1440")
	)
	(layers
		(0 "F.Cu" signal "TOP")
		(4 "In1.Cu" signal "GND")
		(6 "In2.Cu" signal "IN1")
		(8 "In3.Cu" signal "GND1")
		(10 "In4.Cu" signal "IN2")
		(12 "In5.Cu" signal "VCC")
		(14 "In6.Cu" signal "VCC1")
		(16 "In7.Cu" signal "IN3")
		(18 "In8.Cu" signal "GND2")
		(20 "In9.Cu" signal "IN4")
		(22 "In10.Cu" signal "GND3")
		(2 "B.Cu" signal "BOTTOM")
		(9 "F.Adhes" user "F.Adhesive")
		(11 "B.Adhes" user "B.Adhesive")
		(13 "F.Paste" user "Package Geometry/Pastemask Top")
		(15 "B.Paste" user "Package Geometry/Pastemask Bottom")
		(5 "F.SilkS" user "Ref Des/Silkscreen Top")
		(7 "B.SilkS" user "Ref Des/Silkscreen Bottom")
		(1 "F.Mask" user "Board Geometry/Soldermask Top")
		(3 "B.Mask" user "Board Geometry/Soldermask Bottom")
		(17 "Dwgs.User" user "User.Drawings")
		(19 "Cmts.User" user "User.Comments")
		(21 "Eco1.User" user "User.Eco1")
		(23 "Eco2.User" user "User.Eco2")
		(25 "Edge.Cuts" user "Board Geometry/Outline")
		(27 "Margin" user)
		(31 "F.CrtYd" user "Package Geometry/Place Bound Top")
		(29 "B.CrtYd" user "Package Geometry/Place Bound Bottom")
		(35 "F.Fab" user "Ref Des/Assembly Top")
		(33 "B.Fab" user "Ref Des/Assembly Bottom")
	)
	(footprint ""
		(layer "B.Cu")
		(at 54.483 -34.671 90)
		(property "Reference" "R580"
			(at 0 0 90)
			(layer "B.SilkS")
			(hide yes)
			(effects
				(font
					(size 1.27 1.27)
				)
				(justify mirror)
			)
		)
		(property "Value" ""
			(at 0 0 90)
			(layer "B.Fab")
			(effects
				(font
					(size 1.27 1.27)
				)
				(justify mirror)
			)
		)
		(duplicate_pad_numbers_are_jumpers no)
		(fp_line
			(start 0.7874 -0.4064)
			(end -0.7874 -0.4064)
			(stroke
				(width 0.1524)
				(type default)
			)
			(layer "B.SilkS")
		)
		(fp_line
			(start -0.7874 -0.4064)
			(end -0.7874 0.4064)
			(stroke
				(width 0.1524)
				(type default)
			)
			(layer "B.SilkS")
		)
		(fp_line
			(start 0.7874 0.4064)
			(end 0.7874 -0.4064)
			(stroke
				(width 0.1524)
				(type default)
			)
			(layer "B.SilkS")
		)
		(fp_line
			(start -0.7874 0.4064)
			(end 0.7874 0.4064)
			(stroke
				(width 0.1524)
				(type default)
			)
			(layer "B.SilkS")
		)
		(fp_line
			(start 0.67945 -0.305054)
			(end 0.12065 -0.305054)
			(stroke
				(width 0.1)
				(type default)
			)
			(layer "B.Fab")
		)
		(fp_line
			(start 0.12065 -0.305054)
			(end 0.12065 -0.2794)
			(stroke
				(width 0.1)
				(type default)
			)
			(layer "B.Fab")
		)
		(fp_line
			(start -0.12065 -0.3048)
			(end -0.67945 -0.3048)
			(stroke
				(width 0.1)
				(type default)
			)
			(layer "B.Fab")
		)
		(fp_line
			(start -0.67945 -0.3048)
			(end -0.67945 0.3048)
			(stroke
				(width 0.1)
				(type default)
			)
			(layer "B.Fab")
		)
		(fp_line
			(start 0.12065 -0.2794)
			(end -0.12065 -0.2794)
			(stroke
				(width 0.1)
				(type default)
			)
			(layer "B.Fab")
		)
		(fp_line
			(start -0.12065 -0.2794)
			(end -0.12065 -0.3048)
			(stroke
				(width 0.1)
				(type default)
			)
			(layer "B.Fab")
		)
		(fp_line
			(start 0.12065 0.2794)
			(end 0.12065 0.3048)
			(stroke
				(width 0.1)
				(type default)
			)
			(layer "B.Fab")
		)
		(fp_line
			(start -0.120396 0.2794)
			(end 0.12065 0.2794)
			(stroke
				(width 0.1)
				(type default)
			)
			(layer "B.Fab")
		)
		(fp_line
			(start 0.67945 0.3048)
			(end 0.67945 -0.305054)
			(stroke
				(width 0.1)
				(type default)
			)
			(layer "B.Fab")
		)
		(fp_line
			(start 0.12065 0.3048)
			(end 0.67945 0.3048)
			(stroke
				(width 0.1)
				(type default)
			)
			(layer "B.Fab")
		)
		(fp_line
			(start -0.120396 0.3048)
			(end -0.120396 0.2794)
			(stroke
				(width 0.1)
				(type default)
			)
			(layer "B.Fab")
		)
		(fp_line
			(start -0.67945 0.3048)
			(end -0.120396 0.3048)
			(stroke
				(width 0.1)
				(type default)
			)
			(layer "B.Fab")
		)
		(pad "1" smd circle
			(at 0.40005 0 270)
			(size 0 0)
			(layers "B.Cu" "B.Mask" "B.Paste")
			(net "SMB_BMC_MM9_R_SCL")
		)
		(pad "2" smd circle
			(at -0.40005 0 270)
			(size 0 0)
			(layers "B.Cu" "B.Mask" "B.Paste")
			(net "SMB_BMC_MM9_SCL")
		)
	)
	(footprint ""
		(layer "B.Cu")
		(at 61.063378 -46.426628)
		(property "Reference" "C76"
			(at 0 0 0)
			(layer "B.SilkS")
			(hide yes)
			(effects
				(font
					(size 1.27 1.27)
				)
				(justify mirror)
			)
		)
		(property "Value" ""
			(at 0 0 0)
			(layer "B.Fab")
			(effects
				(font
					(size 1.27 1.27)
				)
				(justify mirror)
			)
		)
		(duplicate_pad_numbers_are_jumpers no)
		(fp_line
			(start -0.7874 -0.4064)
			(end -0.7874 0.4064)
			(stroke
				(width 0.1524)
				(type default)
			)
			(layer "B.SilkS")
		)
		(fp_line
			(start -0.7874 0.4064)
			(end 0.7874 0.4064)
			(stroke
				(width 0.1524)
				(type default)
			)
			(layer "B.SilkS")
		)
		(fp_line
			(start 0.7874 -0.4064)
			(end -0.7874 -0.4064)
			(stroke
				(width 0.1524)
				(type default)
			)
			(layer "B.SilkS")
		)
		(fp_line
			(start 0.7874 0.4064)
			(end 0.7874 -0.4064)
			(stroke
				(width 0.1524)
				(type default)
			)
			(layer "B.SilkS")
		)
		(fp_line
			(start -0.67945 -0.3048)
			(end -0.67945 0.3048)
			(stroke
				(width 0.1)
				(type default)
			)
			(layer "B.Fab")
		)
		(fp_line
			(start -0.67945 0.3048)
			(end -0.120396 0.3048)
			(stroke
				(width 0.1)
				(type default)
			)
			(layer "B.Fab")
		)
		(fp_line
			(start -0.12065 -0.3048)
			(end -0.67945 -0.3048)
			(stroke
				(width 0.1)
				(type default)
			)
			(layer "B.Fab")
		)
		(fp_line
			(start -0.12065 -0.2794)
			(end -0.12065 -0.3048)
			(stroke
				(width 0.1)
				(type default)
			)
			(layer "B.Fab")
		)
		(fp_line
			(start -0.120396 0.2794)
			(end 0.12065 0.2794)
			(stroke
				(width 0.1)
				(type default)
			)
			(layer "B.Fab")
		)
		(fp_line
			(start -0.120396 0.3048)
			(end -0.120396 0.2794)
			(stroke
				(width 0.1)
				(type default)
			)
			(layer "B.Fab")
		)
		(fp_line
			(start 0.12065 -0.305054)
			(end 0.12065 -0.2794)
			(stroke
				(width 0.1)
				(type default)
			)
			(layer "B.Fab")
		)
		(fp_line
			(start 0.12065 -0.2794)
			(end -0.12065 -0.2794)
			(stroke
				(width 0.1)
				(type default)
			)
			(layer "B.Fab")
		)
		(fp_line
			(start 0.12065 0.2794)
			(end 0.12065 0.3048)
			(stroke
				(width 0.1)
				(type default)
			)
			(layer "B.Fab")
		)
		(fp_line
			(start 0.12065 0.3048)
			(end 0.67945 0.3048)
			(stroke
				(width 0.1)
				(type default)
			)
			(layer "B.Fab")
		)
		(fp_line
			(start 0.67945 -0.305054)
			(end 0.12065 -0.305054)
			(stroke
				(width 0.1)
				(type default)
			)
			(layer "B.Fab")
		)
		(fp_line
			(start 0.67945 0.3048)
			(end 0.67945 -0.305054)
			(stroke
				(width 0.1)
				(type default)
			)
			(layer "B.Fab")
		)
		(pad "1" smd circle
			(at 0.40005 0 180)
			(size 0 0)
			(layers "B.Cu" "B.Mask" "B.Paste")
			(net "P1V2_AUX")
		)
		(pad "2" smd circle
			(at -0.40005 0 180)
			(size 0 0)
			(layers "B.Cu" "B.Mask" "B.Paste")
			(net "GND")
		)
	)
)
